# S9S_MB_2U (Grand Teton) — schematic netlist excerpt (pin names and nets, part order shuffled) for the footprints in the layout excerpt that follows; sources: Cadence DE-HDL packaged netlist, KiCad conversion of 03242023_DA0F0TMBIJ0_F0T_Motherboard_J_brd_V01_OCP.brd

C725  Q_CAP_DIFFBUS  DIFF BUS_0.22UF 6.3V 20% X6S  pkg C0201  page 176 : \1\ = P5E_CPU1_PE0_TX_C_DP<8> ; \2\ = P5E_CPU1_PE0_TX_DP<8>
C831  Q_CAP_DIFFBUS  DIFF BUS_0.22UF 6.3V 20% X6S  pkg C0201  page 175 : \1\ = P5E_CPU1_PE1_TX_C_DP<3> ; \2\ = P5E_CPU1_PE1_TX_DP<3>
BT1  CONN2_AAABAT029Y19  CONN2_AAA-BAT-029-Y19 IO  pkg BATTERY_AAA-BAT-029-Y19  page 185 : \1\ = P3V_BAT ; \2\ = GND

(kicad_pcb
	(version 20260206)
	(generator "pcbnew")
	(generator_version "10.0")
	(general
		(thickness 1.6)
		(legacy_teardrops no)
	)
	(paper "A4")
	(title_block
		(title "03242023_DA0F0TMBIJ0_F0T_Motherboard_J_brd_V01_OCP.brd")
		(comment 1 "Grand Teton / footprints 2084-2086 of 6105")
	)
	(layers
		(0 "F.Cu" signal "TOP")
		(4 "In1.Cu" signal "GND")
		(6 "In2.Cu" signal "IN1")
		(8 "In3.Cu" signal "GND1")
		(10 "In4.Cu" signal "IN2")
		(12 "In5.Cu" signal "GND2")
		(14 "In6.Cu" signal "IN3")
		(16 "In7.Cu" signal "GND3")
		(18 "In8.Cu" signal "VCC")
		(20 "In9.Cu" signal "VCC1")
		(22 "In10.Cu" signal "GND4")
		(24 "In11.Cu" signal "IN4")
		(26 "In12.Cu" signal "GND5")
		(28 "In13.Cu" signal "IN5")
		(30 "In14.Cu" signal "GND6")
		(32 "In15.Cu" signal "IN6")
		(34 "In16.Cu" signal "GND7")
		(2 "B.Cu" signal "BOTTOM")
		(9 "F.Adhes" user "F.Adhesive")
		(11 "B.Adhes" user "B.Adhesive")
		(13 "F.Paste" user "Package Geometry/Pastemask Top")
		(15 "B.Paste" user "Package Geometry/Pastemask Bottom")
		(5 "F.SilkS" user "Ref Des/Silkscreen Top")
		(7 "B.SilkS" user "Ref Des/Silkscreen Bottom")
		(1 "F.Mask" user "Board Geometry/Soldermask Top")
		(3 "B.Mask" user "Board Geometry/Soldermask Bottom")
		(17 "Dwgs.User" user "User.Drawings")
		(19 "Cmts.User" user "User.Comments")
		(21 "Eco1.User" user "User.Eco1")
		(23 "Eco2.User" user "User.Eco2")
		(25 "Edge.Cuts" user "Board Geometry/Outline")
		(27 "Margin" user)
		(31 "F.CrtYd" user "Package Geometry/Place Bound Top")
		(29 "B.CrtYd" user "Package Geometry/Place Bound Bottom")
		(35 "F.Fab" user "Ref Des/Assembly Top")
		(33 "B.Fab" user "Ref Des/Assembly Bottom")
	)
	(footprint ""
		(layer "F.Cu")
		(at 293.720012 -34.001964 -90)
		(property "Reference" "BT1"
			(at -1.233424 -1.985772 0)
			(unlocked yes)
			(layer "F.SilkS")
			(effects
				(font
					(size 0.7874 0.5842)
					(thickness 0.1524)
				)
				(justify left)
			)
		)
		(property "Value" ""
			(at 0 0 270)
			(layer "F.Fab")
			(effects
				(font
					(size 1.27 1.27)
				)
			)
		)
		(duplicate_pad_numbers_are_jumpers no)
		(fp_line
			(start 3.666236 22.820122)
			(end -3.666236 22.820122)
			(stroke
				(width 0.1524)
				(type default)
			)
			(layer "F.SilkS")
		)
		(fp_line
			(start -4.012692 22.800056)
			(end -3.724148 22.800056)
			(stroke
				(width 0.1524)
				(type default)
			)
			(layer "F.SilkS")
		)
		(fp_line
			(start 3.724148 22.800056)
			(end 4.012692 22.800056)
			(stroke
				(width 0.1524)
				(type default)
			)
			(layer "F.SilkS")
		)
		(fp_line
			(start -3.800094 1.807464)
			(end -3.800094 -1.180084)
			(stroke
				(width 0.1524)
				(type default)
			)
			(layer "F.SilkS")
		)
		(fp_line
			(start 3.899916 1.737614)
			(end 3.899916 -1.260094)
			(stroke
				(width 0.1524)
				(type default)
			)
			(layer "F.SilkS")
		)
		(fp_line
			(start -3.800094 -1.180084)
			(end 3.800094 -1.180084)
			(stroke
				(width 0.1524)
				(type default)
			)
			(layer "F.SilkS")
		)
		(fp_line
			(start 3.800094 -1.180084)
			(end 3.800094 1.807464)
			(stroke
				(width 0.1524)
				(type default)
			)
			(layer "F.SilkS")
		)
		(fp_line
			(start -3.899916 -1.260094)
			(end -3.899916 1.737614)
			(stroke
				(width 0.1524)
				(type default)
			)
			(layer "F.SilkS")
		)
		(fp_line
			(start 3.899916 -1.260094)
			(end -3.899916 -1.260094)
			(stroke
				(width 0.1524)
				(type default)
			)
			(layer "F.SilkS")
		)
		(fp_arc
			(start -3.666236 22.820122)
			(mid -11.149833 12.361061)
			(end -3.800094 1.807464)
			(stroke
				(width 0.1524)
				(type default)
			)
			(layer "F.SilkS")
		)
		(fp_arc
			(start -4.012692 22.800056)
			(mid -11.249872 12.229778)
			(end -3.899916 1.737614)
			(stroke
				(width 0.1524)
				(type default)
			)
			(layer "F.SilkS")
		)
		(fp_arc
			(start 3.800094 1.807464)
			(mid 11.149895 12.361062)
			(end 3.666236 22.820122)
			(stroke
				(width 0.1524)
				(type default)
			)
			(layer "F.SilkS")
		)
		(fp_arc
			(start 3.899916 1.737614)
			(mid 11.249813 12.229779)
			(end 4.012692 22.800056)
			(stroke
				(width 0.1524)
				(type default)
			)
			(layer "F.SilkS")
		)
		(fp_line
			(start 3.666236 22.820122)
			(end -3.666236 22.820122)
			(stroke
				(width 0.1)
				(type default)
			)
			(layer "F.Fab")
		)
		(fp_line
			(start -3.800094 1.807464)
			(end -3.800094 -1.180084)
			(stroke
				(width 0.1)
				(type default)
			)
			(layer "F.Fab")
		)
		(fp_line
			(start -3.800094 -1.180084)
			(end 3.800094 -1.180084)
			(stroke
				(width 0.1)
				(type default)
			)
			(layer "F.Fab")
		)
		(fp_line
			(start 3.800094 -1.180084)
			(end 3.800094 1.807464)
			(stroke
				(width 0.1)
				(type default)
			)
			(layer "F.Fab")
		)
		(fp_arc
			(start -3.666236 22.820122)
			(mid -11.149833 12.361061)
			(end -3.800094 1.807464)
			(stroke
				(width 0.1)
				(type default)
			)
			(layer "F.Fab")
		)
		(fp_arc
			(start 3.800094 1.807464)
			(mid 11.149895 12.361062)
			(end 3.666236 22.820122)
			(stroke
				(width 0.1)
				(type default)
			)
			(layer "F.Fab")
		)
		(fp_text user "-"
			(at 0.26035 22.7076 180)
			(unlocked yes)
			(layer "F.Fab")
			(effects
				(font
					(size 1.905 1.4224)
					(thickness 0.1524)
				)
				(justify left)
			)
		)
		(fp_text user "+"
			(at 0.20955 -2.5908 180)
			(unlocked yes)
			(layer "F.Fab")
			(effects
				(font
					(size 1.905 1.4224)
					(thickness 0.1524)
				)
				(justify left)
			)
		)
		(pad "1" thru_hole rect
			(at 0 0 270)
			(size 1.6256 1.6256)
			(drill 1.1176)
			(layers "*.Cu" "*.Mask")
			(remove_unused_layers no)
			(net "P3V_BAT")
			(clearance 0)
			(padstack
				(mode front_inner_back)
				(layer "Inner"
					(shape circle)
					(size 1.6256 1.6256)
					(clearance 0)
				)
				(layer "B.Cu"
					(shape rect)
					(size 1.6256 1.6256)
					(clearance 0)
				)
			)
		)
		(pad "2" thru_hole circle
			(at 0 19.99996 270)
			(size 1.524 1.524)
			(drill 1.016)
			(layers "*.Cu" "*.Mask")
			(remove_unused_layers no)
			(net "GND")
			(clearance 0)
		)
	)
	(footprint ""
		(layer "F.Cu")
		(at 49.342294 -16.099536 90)
		(property "Reference" "C831"
			(at 0 0 90)
			(layer "F.SilkS")
			(hide yes)
			(effects
				(font
					(size 1.27 1.27)
				)
			)
		)
		(property "Value" ""
			(at 0 0 90)
			(layer "F.Fab")
			(effects
				(font
					(size 1.27 1.27)
				)
			)
		)
		(duplicate_pad_numbers_are_jumpers no)
		(fp_line
			(start 0.299974 -0.150114)
			(end 0.299974 0.150114)
			(stroke
				(width 0.1)
				(type default)
			)
			(layer "F.Fab")
		)
		(fp_line
			(start -0.299974 -0.150114)
			(end 0.299974 -0.150114)
			(stroke
				(width 0.1)
				(type default)
			)
			(layer "F.Fab")
		)
		(fp_line
			(start 0.299974 0.150114)
			(end -0.299974 0.150114)
			(stroke
				(width 0.1)
				(type default)
			)
			(layer "F.Fab")
		)
		(fp_line
			(start -0.299974 0.150114)
			(end -0.299974 -0.150114)
			(stroke
				(width 0.1)
				(type default)
			)
			(layer "F.Fab")
		)
		(pad "1" smd rect
			(at -0.2667 0 90)
			(size 0.3048 0.381)
			(layers "F.Cu" "F.Mask" "F.Paste")
			(net "P5E_CPU1_PE1_TX_C_DP<3>")
		)
		(pad "2" smd rect
			(at 0.2667 0 90)
			(size 0.3048 0.381)
			(layers "F.Cu" "F.Mask" "F.Paste")
			(net "P5E_CPU1_PE1_TX_DP<3>")
		)
	)
	(footprint ""
		(layer "F.Cu")
		(at 70.311518 -402.371052 -90)
		(property "Reference" "C725"
			(at 0 0 270)
			(layer "F.SilkS")
			(hide yes)
			(effects
				(font
					(size 1.27 1.27)
				)
			)
		)
		(property "Value" ""
			(at 0 0 270)
			(layer "F.Fab")
			(effects
				(font
					(size 1.27 1.27)
				)
			)
		)
		(duplicate_pad_numbers_are_jumpers no)
		(fp_line
			(start -0.299974 0.150114)
			(end -0.299974 -0.150114)
			(stroke
				(width 0.1)
				(type default)
			)
			(layer "F.Fab")
		)
		(fp_line
			(start 0.299974 0.150114)
			(end -0.299974 0.150114)
			(stroke
				(width 0.1)
				(type default)
			)
			(layer "F.Fab")
		)
		(fp_line
			(start -0.299974 -0.150114)
			(end 0.299974 -0.150114)
			(stroke
				(width 0.1)
				(type default)
			)
			(layer "F.Fab")
		)
		(fp_line
			(start 0.299974 -0.150114)
			(end 0.299974 0.150114)
			(stroke
				(width 0.1)
				(type default)
			)
			(layer "F.Fab")
		)
		(pad "1" smd rect
			(at -0.2667 0 270)
			(size 0.3048 0.381)
			(layers "F.Cu" "F.Mask" "F.Paste")
			(net "P5E_CPU1_PE0_TX_C_DP<8>")
		)
		(pad "2" smd rect
			(at 0.2667 0 270)
			(size 0.3048 0.381)
			(layers "F.Cu" "F.Mask" "F.Paste")
			(net "P5E_CPU1_PE0_TX_DP<8>")
		)
	)
)
